# T6G (Grand Teton) — schematic netlist excerpt (pin names and nets, part order shuffled) for the footprints in the layout excerpt that follows; sources: Cadence DE-HDL packaged netlist, KiCad conversion of 04192023_DAF0TMB3IC0_F0TG_MB_C_brd_V02_OCP.brd

R4501  Q_RES  0 5% CHIP  pkg 0402LF  page 233 : A = CLK_GEN2_XTAL_IN_R ; B = CLK_GEN2_XTAL_IN
R3463  Q_RES  54.9K 1% CHIP  pkg 0402LF  page 126 : A = GPU_BASE_HMC_READY ; B = GND

(kicad_pcb
	(version 20260206)
	(generator "pcbnew")
	(generator_version "10.0")
	(general
		(thickness 1.6)
		(legacy_teardrops no)
	)
	(paper "A4")
	(title_block
		(title "04192023_DAF0TMB3IC0_F0TG_MB_C_brd_V02_OCP.brd")
		(comment 1 "Grand Teton / footprints 4058-4059 of 8354")
	)
	(layers
		(0 "F.Cu" signal "TOP")
		(4 "In1.Cu" signal "GND")
		(6 "In2.Cu" signal "IN1")
		(8 "In3.Cu" signal "GND1")
		(10 "In4.Cu" signal "IN2")
		(12 "In5.Cu" signal "GND2")
		(14 "In6.Cu" signal "IN3")
		(16 "In7.Cu" signal "GND3")
		(18 "In8.Cu" signal "VCC")
		(20 "In9.Cu" signal "VCC1")
		(22 "In10.Cu" signal "GND4")
		(24 "In11.Cu" signal "IN4")
		(26 "In12.Cu" signal "GND5")
		(28 "In13.Cu" signal "IN5")
		(30 "In14.Cu" signal "GND6")
		(32 "In15.Cu" signal "IN6")
		(34 "In16.Cu" signal "GND7")
		(2 "B.Cu" signal "BOTTOM")
		(9 "F.Adhes" user "F.Adhesive")
		(11 "B.Adhes" user "B.Adhesive")
		(13 "F.Paste" user "Package Geometry/Pastemask Top")
		(15 "B.Paste" user "Package Geometry/Pastemask Bottom")
		(5 "F.SilkS" user "Ref Des/Silkscreen Top")
		(7 "B.SilkS" user "Ref Des/Silkscreen Bottom")
		(1 "F.Mask" user "Board Geometry/Soldermask Top")
		(3 "B.Mask" user "Board Geometry/Soldermask Bottom")
		(17 "Dwgs.User" user "User.Drawings")
		(19 "Cmts.User" user "User.Comments")
		(21 "Eco1.User" user "User.Eco1")
		(23 "Eco2.User" user "User.Eco2")
		(25 "Edge.Cuts" user "Board Geometry/Outline")
		(27 "Margin" user)
		(31 "F.CrtYd" user "Package Geometry/Place Bound Top")
		(29 "B.CrtYd" user "Package Geometry/Place Bound Bottom")
		(35 "F.Fab" user "Ref Des/Assembly Top")
		(33 "B.Fab" user "Ref Des/Assembly Bottom")
	)
	(footprint ""
		(layer "F.Cu")
		(at 165.2016 -437.423052)
		(property "Reference" "R3463"
			(at 0 0 0)
			(layer "F.SilkS")
			(hide yes)
			(effects
				(font
					(size 1.27 1.27)
				)
			)
		)
		(property "Value" ""
			(at 0 0 0)
			(layer "F.Fab")
			(effects
				(font
					(size 1.27 1.27)
				)
			)
		)
		(duplicate_pad_numbers_are_jumpers no)
		(fp_line
			(start -0.7874 -0.4064)
			(end 0.7874 -0.4064)
			(stroke
				(width 0.1524)
				(type default)
			)
			(layer "F.SilkS")
		)
		(fp_line
			(start -0.7874 0.4064)
			(end -0.7874 -0.4064)
			(stroke
				(width 0.1524)
				(type default)
			)
			(layer "F.SilkS")
		)
		(fp_line
			(start 0.7874 -0.4064)
			(end 0.7874 0.4064)
			(stroke
				(width 0.1524)
				(type default)
			)
			(layer "F.SilkS")
		)
		(fp_line
			(start 0.7874 0.4064)
			(end -0.7874 0.4064)
			(stroke
				(width 0.1524)
				(type default)
			)
			(layer "F.SilkS")
		)
		(fp_line
			(start -0.67945 -0.305054)
			(end -0.12065 -0.305054)
			(stroke
				(width 0.1)
				(type default)
			)
			(layer "F.Fab")
		)
		(fp_line
			(start -0.67945 0.3048)
			(end -0.67945 -0.305054)
			(stroke
				(width 0.1)
				(type default)
			)
			(layer "F.Fab")
		)
		(fp_line
			(start -0.12065 -0.305054)
			(end -0.12065 -0.2794)
			(stroke
				(width 0.1)
				(type default)
			)
			(layer "F.Fab")
		)
		(fp_line
			(start -0.12065 -0.2794)
			(end 0.12065 -0.2794)
			(stroke
				(width 0.1)
				(type default)
			)
			(layer "F.Fab")
		)
		(fp_line
			(start -0.12065 0.2794)
			(end -0.12065 0.3048)
			(stroke
				(width 0.1)
				(type default)
			)
			(layer "F.Fab")
		)
		(fp_line
			(start -0.12065 0.3048)
			(end -0.67945 0.3048)
			(stroke
				(width 0.1)
				(type default)
			)
			(layer "F.Fab")
		)
		(fp_line
			(start 0.120396 0.2794)
			(end -0.12065 0.2794)
			(stroke
				(width 0.1)
				(type default)
			)
			(layer "F.Fab")
		)
		(fp_line
			(start 0.120396 0.3048)
			(end 0.120396 0.2794)
			(stroke
				(width 0.1)
				(type default)
			)
			(layer "F.Fab")
		)
		(fp_line
			(start 0.12065 -0.3048)
			(end 0.67945 -0.3048)
			(stroke
				(width 0.1)
				(type default)
			)
			(layer "F.Fab")
		)
		(fp_line
			(start 0.12065 -0.2794)
			(end 0.12065 -0.3048)
			(stroke
				(width 0.1)
				(type default)
			)
			(layer "F.Fab")
		)
		(fp_line
			(start 0.67945 -0.3048)
			(end 0.67945 0.3048)
			(stroke
				(width 0.1)
				(type default)
			)
			(layer "F.Fab")
		)
		(fp_line
			(start 0.67945 0.3048)
			(end 0.120396 0.3048)
			(stroke
				(width 0.1)
				(type default)
			)
			(layer "F.Fab")
		)
		(pad "1" smd circle
			(at -0.40005 0)
			(size 0 0)
			(layers "F.Cu" "F.Mask" "F.Paste")
			(net "GPU_BASE_HMC_READY")
		)
		(pad "2" smd circle
			(at 0.40005 0)
			(size 0 0)
			(layers "F.Cu" "F.Mask" "F.Paste")
			(net "GND")
		)
	)
	(footprint ""
		(layer "F.Cu")
		(at 9.238488 -135.32993 90)
		(property "Reference" "R4501"
			(at 0 0 90)
			(layer "F.SilkS")
			(hide yes)
			(effects
				(font
					(size 1.27 1.27)
				)
			)
		)
		(property "Value" ""
			(at 0 0 90)
			(layer "F.Fab")
			(effects
				(font
					(size 1.27 1.27)
				)
			)
		)
		(duplicate_pad_numbers_are_jumpers no)
		(fp_line
			(start 0.7874 -0.4064)
			(end 0.7874 0.4064)
			(stroke
				(width 0.1524)
				(type default)
			)
			(layer "F.SilkS")
		)
		(fp_line
			(start -0.7874 -0.4064)
			(end 0.7874 -0.4064)
			(stroke
				(width 0.1524)
				(type default)
			)
			(layer "F.SilkS")
		)
		(fp_line
			(start 0.7874 0.4064)
			(end -0.7874 0.4064)
			(stroke
				(width 0.1524)
				(type default)
			)
			(layer "F.SilkS")
		)
		(fp_line
			(start -0.7874 0.4064)
			(end -0.7874 -0.4064)
			(stroke
				(width 0.1524)
				(type default)
			)
			(layer "F.SilkS")
		)
		(fp_line
			(start -0.12065 -0.305054)
			(end -0.12065 -0.2794)
			(stroke
				(width 0.1)
				(type default)
			)
			(layer "F.Fab")
		)
		(fp_line
			(start -0.67945 -0.305054)
			(end -0.12065 -0.305054)
			(stroke
				(width 0.1)
				(type default)
			)
			(layer "F.Fab")
		)
		(fp_line
			(start 0.67945 -0.3048)
			(end 0.67945 0.3048)
			(stroke
				(width 0.1)
				(type default)
			)
			(layer "F.Fab")
		)
		(fp_line
			(start 0.12065 -0.3048)
			(end 0.67945 -0.3048)
			(stroke
				(width 0.1)
				(type default)
			)
			(layer "F.Fab")
		)
		(fp_line
			(start 0.12065 -0.2794)
			(end 0.12065 -0.3048)
			(stroke
				(width 0.1)
				(type default)
			)
			(layer "F.Fab")
		)
		(fp_line
			(start -0.12065 -0.2794)
			(end 0.12065 -0.2794)
			(stroke
				(width 0.1)
				(type default)
			)
			(layer "F.Fab")
		)
		(fp_line
			(start 0.120396 0.2794)
			(end -0.12065 0.2794)
			(stroke
				(width 0.1)
				(type default)
			)
			(layer "F.Fab")
		)
		(fp_line
			(start -0.12065 0.2794)
			(end -0.12065 0.3048)
			(stroke
				(width 0.1)
				(type default)
			)
			(layer "F.Fab")
		)
		(fp_line
			(start 0.67945 0.3048)
			(end 0.120396 0.3048)
			(stroke
				(width 0.1)
				(type default)
			)
			(layer "F.Fab")
		)
		(fp_line
			(start 0.120396 0.3048)
			(end 0.120396 0.2794)
			(stroke
				(width 0.1)
				(type default)
			)
			(layer "F.Fab")
		)
		(fp_line
			(start -0.12065 0.3048)
			(end -0.67945 0.3048)
			(stroke
				(width 0.1)
				(type default)
			)
			(layer "F.Fab")
		)
		(fp_line
			(start -0.67945 0.3048)
			(end -0.67945 -0.305054)
			(stroke
				(width 0.1)
				(type default)
			)
			(layer "F.Fab")
		)
		(pad "1" smd circle
			(at -0.40005 0 90)
			(size 0 0)
			(layers "F.Cu" "F.Mask" "F.Paste")
			(net "CLK_GEN2_XTAL_IN_R")
		)
		(pad "2" smd circle
			(at 0.40005 0 90)
			(size 0 0)
			(layers "F.Cu" "F.Mask" "F.Paste")
			(net "CLK_GEN2_XTAL_IN")
		)
	)
)
